# T6G (Grand Teton) — schematic parts with pin connectivity, parts 2609–2609 of 8303; source: Cadence DE-HDL packaged netlist (pstxprt.dat, pstxnet.dat, pstchip.dat)

J29  SCONN288_DDR506112002KQ  IO  pkg DDR288S_1-1VXC  page 107
  1  VIN_BULK0  POWER  = P12V_MEM_CPU1
  2  RFU0  TRI  = NC
  3  VIN_MGMT  POWER  = P3V3_AUX
  4  HSCL  IN  = I3C_SPD_DDRJ_CPU1_SCL
  5  HSDA  BI  = I3C_SPD_DDRJ_CPU1_SDA
  6  VSS0  POWER  = GND
  7  DQ0_A  BI  = M_J_CPU1_SA_DQ<0>
  8  VSS1  POWER  = GND
  9  DQ1_A  BI  = M_J_CPU1_SA_DQ<1>
  10  VSS2  POWER  = GND
  11  DQS0_A_T  BI  = M_J_CPU1_SA_DQS_DP<0>
  12  DQS0_A_C  BI  = M_J_CPU1_SA_DQS_DN<0>
  13  VSS3  POWER  = GND
  14  DQ4_A  BI  = M_J_CPU1_SA_DQ<4>
  15  VSS4  POWER  = GND
  16  DQ5_A  BI  = M_J_CPU1_SA_DQ<5>
  17  VSS5  POWER  = GND
  18  DQ8_A  BI  = M_J_CPU1_SA_DQ<8>
  19  VSS6  POWER  = GND
  20  DQ9_A  BI  = M_J_CPU1_SA_DQ<9>
  21  VSS7  POWER  = GND
  22  DQS1_A_T  BI  = M_J_CPU1_SA_DQS_DP<1>
  23  DQS1_A_C  BI  = M_J_CPU1_SA_DQS_DN<1>
  24  VSS8  POWER  = GND
  25  DQ12_A  BI  = M_J_CPU1_SA_DQ<12>
  26  VSS9  POWER  = GND
  27  DQ13_A  BI  = M_J_CPU1_SA_DQ<13>
  28  VSS10  POWER  = GND
  29  DQ16_A  BI  = M_J_CPU1_SA_DQ<16>
  30  VSS11  POWER  = GND
  31  DQ17_A  BI  = M_J_CPU1_SA_DQ<17>
  32  VSS12  POWER  = GND
  33  DQS2_A_T  BI  = M_J_CPU1_SA_DQS_DP<2>
  34  DQS2_A_C  BI  = M_J_CPU1_SA_DQS_DN<2>
  35  VSS13  POWER  = GND
  36  DQ20_A  BI  = M_J_CPU1_SA_DQ<20>
  37  VSS14  POWER  = GND
  38  DQ21_A  BI  = M_J_CPU1_SA_DQ<21>
  39  VSS15  POWER  = GND
  40  DQ24_A  BI  = M_J_CPU1_SA_DQ<24>
  41  VSS16  POWER  = GND
  42  DQ25_A  BI  = M_J_CPU1_SA_DQ<25>
  43  VSS17  POWER  = GND
  44  DQS3_A_T  BI  = M_J_CPU1_SA_DQS_DP<3>
  45  DQS3_A_C  BI  = M_J_CPU1_SA_DQS_DN<3>
  46  VSS18  POWER  = GND
  47  DQ28_A  BI  = M_J_CPU1_SA_DQ<28>
  48  VSS19  POWER  = GND
  49  DQ29_A  BI  = M_J_CPU1_SA_DQ<29>
  50  VSS20  POWER  = GND
  51  CB0_A  BI  = M_J_CPU1_SA_CB<0>
  52  VSS21  POWER  = GND
  53  CB1_A  BI  = M_J_CPU1_SA_CB<1>
  54  VSS22  POWER  = GND
  55  DQS4_A_T  BI  = M_J_CPU1_SA_DQS_DP<4>
  56  DQS4_A_C  BI  = M_J_CPU1_SA_DQS_DN<4>
  57  VSS23  POWER  = GND
  58  CB4_A  BI  = M_J_CPU1_SA_CB<4>
  59  VSS24  POWER  = GND
  60  CB5_A  BI  = M_J_CPU1_SA_CB<5>
  61  VSS25  POWER  = GND
  62  ALERT_N  OUT  = M_J_CPU1_ALERT_N
  63  VSS26  POWER  = GND
  64  CS0_A_N  IN  = M_J_CPU1_SA_CS_N<0>
  65  VSS27  POWER  = GND
  66  CA0_A  IN  = M_J_CPU1_SA_CA<0>
  67  VSS28  POWER  = GND
  68  CA2_A  IN  = M_J_CPU1_SA_CA<2>
  69  VSS29  POWER  = GND
  70  CA4_A  IN  = M_J_CPU1_SA_CA<4>
  71  VSS30  POWER  = GND
  72  CA6_A  IN  = M_J_CPU1_SA_CA<6>
  73  VSS31  POWER  = GND
  74  PAR_A  IN  = M_J_CPU1_SA_PAR
  75  VSS32  POWER  = GND
  76  CA0_B  IN  = M_J_CPU1_SB_CA<0>
  77  VSS33  POWER  = GND
  78  CA2_B  IN  = M_J_CPU1_SB_CA<2>
  79  VSS34  POWER  = GND
  80  CA4_B  IN  = M_J_CPU1_SB_CA<4>
  81  VSS35  POWER  = GND
  82  CA6_B  IN  = M_J_CPU1_SB_CA<6>
  83  VSS36  POWER  = GND
  84  CS0_B_N  IN  = M_J_CPU1_SB_CS_N<0>
  85  VSS37  POWER  = GND
  86  \lbd||rsp_a_n\  OUT  = M_J_CPU1_SA_RSP<0>
  87  \lbs||rsp_b_n\  OUT  = M_J_CPU1_SB_RSP<0>
  88  VSS38  POWER  = GND
  89  CB4_B  BI  = M_J_CPU1_SB_CB<4>
  90  VSS39  POWER  = GND
  91  CB5_B  BI  = M_J_CPU1_SB_CB<5>
  92  VSS40  POWER  = GND
  93  \dqs9_b_t||tdqs9_b_t||dbi4_b_n\  BI  = M_J_CPU1_SB_DQS_DP<9>
  94  \dqs9_b_c||tdqs9_b_c\  BI  = M_J_CPU1_SB_DQS_DN<9>
  95  VSS41  POWER  = GND
  96  CB0_B  BI  = M_J_CPU1_SB_CB<0>
  97  VSS42  POWER  = GND
  98  CB1_B  BI  = M_J_CPU1_SB_CB<1>
  99  VSS43  POWER  = GND
  100  DQ0_B  BI  = M_J_CPU1_SB_DQ<0>
  101  VSS44  POWER  = GND
  102  DQ1_B  BI  = M_J_CPU1_SB_DQ<1>
  103  VSS45  POWER  = GND
  104  DQS0_B_T  BI  = M_J_CPU1_SB_DQS_DP<0>
  105  DQS0_B_C  BI  = M_J_CPU1_SB_DQS_DN<0>
  106  VSS46  POWER  = GND
  107  DQ4_B  BI  = M_J_CPU1_SB_DQ<4>
  108  VSS47  POWER  = GND
  109  DQ5_B  BI  = M_J_CPU1_SB_DQ<5>
  110  VSS48  POWER  = GND
  111  DQ8_B  BI  = M_J_CPU1_SB_DQ<8>
  112  VSS49  POWER  = GND
  113  DQ9_B  BI  = M_J_CPU1_SB_DQ<9>
  114  VSS50  POWER  = GND
  115  DQS1_B_T  BI  = M_J_CPU1_SB_DQS_DP<1>
  116  DQS1_B_C  BI  = M_J_CPU1_SB_DQS_DN<1>
  117  VSS51  POWER  = GND
  118  DQ12_B  BI  = M_J_CPU1_SB_DQ<12>
  119  VSS52  POWER  = GND
  120  DQ13_B  BI  = M_J_CPU1_SB_DQ<13>
  121  VSS53  POWER  = GND
  122  DQ16_B  BI  = M_J_CPU1_SB_DQ<16>
  123  VSS54  POWER  = GND
  124  DQ17_B  BI  = M_J_CPU1_SB_DQ<17>
  125  VSS55  POWER  = GND
  126  DQS2_B_T  BI  = M_J_CPU1_SB_DQS_DP<2>
  127  DQS2_B_C  BI  = M_J_CPU1_SB_DQS_DN<2>
  128  VSS56  POWER  = GND
  129  DQ20_B  BI  = M_J_CPU1_SB_DQ<20>
  130  VSS57  POWER  = GND
  131  DQ21_B  BI  = M_J_CPU1_SB_DQ<21>
  132  VSS58  POWER  = GND
  133  DQ24_B  BI  = M_J_CPU1_SB_DQ<24>
  134  VSS59  POWER  = GND
  135  DQ25_B  BI  = M_J_CPU1_SB_DQ<25>
  136  VSS60  POWER  = GND
  137  DQS3_B_T  BI  = M_J_CPU1_SB_DQS_DP<3>
  138  DQS3_B_C  BI  = M_J_CPU1_SB_DQS_DN<3>
  139  VSS61  POWER  = GND
  140  DQ28_B  BI  = M_J_CPU1_SB_DQ<28>
  141  VSS62  POWER  = GND
  142  DQ29_B  BI  = M_J_CPU1_SB_DQ<29>
  143  VSS63  POWER  = GND
  144  RFU1  TRI  = NC
  145  VIN_BULK1  POWER  = P12V_MEM_CPU1
  146  VIN_BULK2  POWER  = P12V_MEM_CPU1
  147  \pwr_good||fail_n\  BI  = PWRGD_CHJ_CPU1_DIMM
  148  HAS  IN  = PD_CHJ_CPU1_DIMM_SAA
  149  RFU2  TRI  = NC
  150  RFU3  TRI  = NC
  151  VSS64  POWER  = GND
  152  DQ2_A  BI  = M_J_CPU1_SA_DQ<2>
  153  VSS65  POWER  = GND
  154  DQ3_A  BI  = M_J_CPU1_SA_DQ<3>
  155  VSS66  POWER  = GND
  156  \dqs5_a_c||tdqs5_a_c||dqs5_a_t||tdqs5_a_t\  BI  = M_J_CPU1_SA_DQS_DN<5>
  157  \dqs5_a_t||tdqs5_a_t\  BI  = M_J_CPU1_SA_DQS_DP<5>
  158  VSS67  POWER  = GND
  159  DQ6_A  BI  = M_J_CPU1_SA_DQ<6>
  160  VSS68  POWER  = GND
  161  DQ7_A  BI  = M_J_CPU1_SA_DQ<7>
  162  VSS69  POWER  = GND
  163  DQ10_A  BI  = M_J_CPU1_SA_DQ<10>
  164  VSS70  POWER  = GND
  165  DQ11_A  BI  = M_J_CPU1_SA_DQ<11>
  166  VSS71  POWER  = GND
  167  \dqs6_a_c||tdqs6_a_c||dqs6_a_t||tdqs6_a_t\  BI  = M_J_CPU1_SA_DQS_DN<6>
  168  \dqs6_a_t||tdqs6_a_t\  BI  = M_J_CPU1_SA_DQS_DP<6>
  169  VSS72  POWER  = GND
  170  DQ14_A  BI  = M_J_CPU1_SA_DQ<14>
  171  VSS73  POWER  = GND
  172  DQ15_A  BI  = M_J_CPU1_SA_DQ<15>
  173  VSS74  POWER  = GND
  174  DQ18_A  BI  = M_J_CPU1_SA_DQ<18>
  175  VSS75  POWER  = GND
  176  DQ19_A  BI  = M_J_CPU1_SA_DQ<19>
  177  VSS76  POWER  = GND
  178  \dqs7_a_c||tdqs7_a_c\  BI  = M_J_CPU1_SA_DQS_DN<7>
  179  \dqs7_a_t||tdqs7_a_t\  BI  = M_J_CPU1_SA_DQS_DP<7>
  180  VSS77  POWER  = GND
  181  DQ22_A  BI  = M_J_CPU1_SA_DQ<22>
  182  VSS78  POWER  = GND
  183  DQ23_A  BI  = M_J_CPU1_SA_DQ<23>
  184  VSS79  POWER  = GND
  185  DQ26_A  BI  = M_J_CPU1_SA_DQ<26>
  186  VSS80  POWER  = GND
  187  DQ27_A  BI  = M_J_CPU1_SA_DQ<27>
  188  VSS81  POWER  = GND
  189  \dqs8_a_c||tdqs8_a_c\  BI  = M_J_CPU1_SA_DQS_DN<8>
  190  \dqs8_a_t||tdqs8_a_t\  BI  = M_J_CPU1_SA_DQS_DP<8>
  191  VSS82  POWER  = GND
  192  DQ30_A  BI  = M_J_CPU1_SA_DQ<30>
  193  VSS83  POWER  = GND
  194  DQ31_A  BI  = M_J_CPU1_SA_DQ<31>
  195  VSS84  POWER  = GND
  196  CB2_A  BI  = M_J_CPU1_SA_CB<2>
  197  VSS85  POWER  = GND
  198  CB3_A  BI  = M_J_CPU1_SA_CB<3>
  199  VSS86  POWER  = GND
  200  \dqs9_a_c||tdqs9_a_c\  BI  = M_J_CPU1_SA_DQS_DN<9>
  201  \dqs9_a_t||tdqs9_a_t\  BI  = M_J_CPU1_SA_DQS_DP<9>
  202  VSS87  POWER  = GND
  203  CB6_A  BI  = M_J_CPU1_SA_CB<6>
  204  VSS88  POWER  = GND
  205  CB7_A  BI  = M_J_CPU1_SA_CB<7>
  206  VSS89  POWER  = GND
  207  RESET_N  IN  = M_J_CPU1_RESET_N
  208  VSS90  POWER  = GND
  209  CS1_A_N  IN  = M_J_CPU1_SA_CS_N<1>
  210  VSS91  POWER  = GND
  211  CA1_A  IN  = M_J_CPU1_SA_CA<1>
  212  VSS92  POWER  = GND
  213  CA3_A  IN  = M_J_CPU1_SA_CA<3>
  214  VSS93  POWER  = GND
  215  CA5_A  IN  = M_J_CPU1_SA_CA<5>
  216  VSS94  POWER  = GND
  217  CK_T  IN  = M_J_CPU1_CLK_DP<0>
  218  CK_C  IN  = M_J_CPU1_CLK_DN<0>
  219  VSS95  POWER  = GND
  220  RFU4  TRI  = NC
  221  CA1_B  IN  = M_J_CPU1_SB_CA<1>
  222  VSS96  POWER  = GND
  223  CA3_B  IN  = M_J_CPU1_SB_CA<3>
  224  VSS97  POWER  = GND
  225  CA5_B  IN  = M_J_CPU1_SB_CA<5>
  226  VSS98  POWER  = GND
  227  PAR_B  IN  = M_J_CPU1_SB_PAR
  228  VSS99  POWER  = GND
  229  CS1_B_N  IN  = M_J_CPU1_SB_CS_N<1>
  230  VSS100  POWER  = GND
  231  RFU5  TRI  = NC
  232  RFU6  TRI  = NC
  233  VSS101  POWER  = GND
  234  CB6_B  BI  = M_J_CPU1_SB_CB<6>
  235  VSS102  POWER  = GND
  236  CB7_B  BI  = M_J_CPU1_SB_CB<7>
  237  VSS103  POWER  = GND
  238  DQS4_B_C  BI  = M_J_CPU1_SB_DQS_DN<4>
  239  DQS4_B_T  BI  = M_J_CPU1_SB_DQS_DP<4>
  240  VSS104  POWER  = GND
  241  CB2_B  BI  = M_J_CPU1_SB_CB<2>
  242  VSS105  POWER  = GND
  243  CB3_B  BI  = M_J_CPU1_SB_CB<3>
  244  VSS106  POWER  = GND
  245  DQ2_B  BI  = M_J_CPU1_SB_DQ<2>
  246  VSS107  POWER  = GND
  247  DQ3_B  BI  = M_J_CPU1_SB_DQ<3>
  248  VSS108  POWER  = GND
  249  \dqs5_b_c||tdqs5_b_c\  BI  = M_J_CPU1_SB_DQS_DN<5>
  250  \dqs5_b_t||tdqs5_b_t\  BI  = M_J_CPU1_SB_DQS_DP<5>
  251  VSS109  POWER  = GND
  252  DQ6_B  BI  = M_J_CPU1_SB_DQ<6>
  253  VSS110  POWER  = GND
  254  DQ7_B  BI  = M_J_CPU1_SB_DQ<7>
  255  VSS111  POWER  = GND
  256  DQ10_B  BI  = M_J_CPU1_SB_DQ<10>
  257  VSS112  POWER  = GND
  258  DQ11_B  BI  = M_J_CPU1_SB_DQ<11>
  259  VSS113  POWER  = GND
  260  \dqs6_b_c||tdqs6_b_c\  BI  = M_J_CPU1_SB_DQS_DN<6>
  261  \dqs6_b_t||tdqs6_b_t\  BI  = M_J_CPU1_SB_DQS_DP<6>
  262  VSS114  POWER  = GND
  263  DQ14_B  BI  = M_J_CPU1_SB_DQ<14>
  264  VSS115  POWER  = GND
  265  DQ15_B  BI  = M_J_CPU1_SB_DQ<15>
  266  VSS116  POWER  = GND
  267  DQ18_B  BI  = M_J_CPU1_SB_DQ<18>
  268  VSS117  POWER  = GND
  269  DQ19_B  BI  = M_J_CPU1_SB_DQ<19>
  270  VSS118  POWER  = GND
  271  \dqs7_b_c||tdqs7_b_c\  BI  = M_J_CPU1_SB_DQS_DN<7>
  272  \dqs7_b_t||tdqs7_b_t\  BI  = M_J_CPU1_SB_DQS_DP<7>
  273  VSS119  POWER  = GND
  274  DQ22_B  BI  = M_J_CPU1_SB_DQ<22>
  275  VSS120  POWER  = GND
  276  DQ23_B  BI  = M_J_CPU1_SB_DQ<23>
  277  VSS121  POWER  = GND
  278  DQ26_B  BI  = M_J_CPU1_SB_DQ<26>
  279  VSS122  POWER  = GND
  280  DQ27_B  BI  = M_J_CPU1_SB_DQ<27>
  281  VSS123  POWER  = GND
  282  \dqs8_b_c||tdqs8_b_c\  BI  = M_J_CPU1_SB_DQS_DN<8>
  283  \dqs8_b_t||tdqs8_b_t\  BI  = M_J_CPU1_SB_DQS_DP<8>
  284  VSS124  POWER  = GND
  285  DQ30_B  BI  = M_J_CPU1_SB_DQ<30>
  286  VSS125  POWER  = GND
  287  DQ31_B  BI  = M_J_CPU1_SB_DQ<31>
  288  VSS126  POWER  = GND
  G1  G1  POWER  = GND
  G2  G2  POWER  = GND
  G3  G3  POWER  = GND
